(kicad_pcb
	(version 20260206)
	(generator "pcbnew")
	(generator_version "10.0")
	(general
		(thickness 1.21888)
		(legacy_teardrops no)
	)
	(paper "A4")
	(title_block
		(title "timecard-v8 — TimeCard-DC-V8_EXP.PcbDoc")
		(comment 1 "Time Appliance Project (Time Card) / footprints 168-174 of 288")
	)
	(layers
		(0 "F.Cu" signal "TOP")
		(4 "In1.Cu" signal "SGND")
		(6 "In2.Cu" signal "IN1")
		(8 "In3.Cu" signal "IN2")
		(10 "In4.Cu" signal "SGND1")
		(2 "B.Cu" signal "BOTTOM")
		(9 "F.Adhes" user "F.Adhesive")
		(11 "B.Adhes" user "B.Adhesive")
		(13 "F.Paste" user "Top Paste")
		(15 "B.Paste" user "Bottom Paste")
		(5 "F.SilkS" user "Top Overlay")
		(7 "B.SilkS" user "Bottom Overlay")
		(1 "F.Mask" user "Top Solder")
		(3 "B.Mask" user "Bottom Solder")
		(17 "Dwgs.User" user "User.Drawings")
		(19 "Cmts.User" user "User.Comments")
		(21 "Eco1.User" user "User.Eco1")
		(23 "Eco2.User" user "User.Eco2")
		(25 "Edge.Cuts" user)
		(27 "Margin" user)
		(31 "F.CrtYd" user "Top Courtyard")
		(29 "B.CrtYd" user "Bottom Courtyard")
		(35 "F.Fab" user "Top Component Center")
		(33 "B.Fab" user "Bottom Component Center")
	)
	(footprint "IS32FL3207:IS32FL3207"
		(layer "F.Cu")
		(at 89.3761 87.1162)
		(property "Reference" "U6"
			(at -2.271395 -3.723079 0)
			(unlocked yes)
			(layer "F.SilkS")
			(effects
				(font
					(size 0.762 0.762)
					(thickness 0.2286)
				)
			)
		)
		(property "Value" "IS32FL3207"
			(at 4.17596 4.662671 0)
			(unlocked yes)
			(layer "F.SilkS")
			(hide yes)
			(effects
				(font
					(size 0.762 0.762)
					(thickness 0.2286)
				)
			)
		)
		(sheetname "USER_IO_STATUS")
		(sheetfile "USER_IO_STATUS.kicad_sch")
		(duplicate_pad_numbers_are_jumpers no)
		(fp_line
			(start -2.65 -2.65)
			(end -2.05 -2.65)
			(stroke
				(width 0.2)
				(type solid)
			)
			(layer "F.SilkS")
		)
		(fp_line
			(start -2.65 -2.05)
			(end -2.65 -2.65)
			(stroke
				(width 0.2)
				(type solid)
			)
			(layer "F.SilkS")
		)
		(fp_line
			(start -2.65 2.65)
			(end -2.65 2.05)
			(stroke
				(width 0.2)
				(type solid)
			)
			(layer "F.SilkS")
		)
		(fp_line
			(start -2.65 2.65)
			(end -2.05 2.65)
			(stroke
				(width 0.2)
				(type solid)
			)
			(layer "F.SilkS")
		)
		(fp_line
			(start 2.05 -2.65)
			(end 2.65 -2.65)
			(stroke
				(width 0.2)
				(type solid)
			)
			(layer "F.SilkS")
		)
		(fp_line
			(start 2.05 2.65)
			(end 2.65 2.65)
			(stroke
				(width 0.2)
				(type solid)
			)
			(layer "F.SilkS")
		)
		(fp_line
			(start 2.65 -2.05)
			(end 2.65 -2.65)
			(stroke
				(width 0.2)
				(type solid)
			)
			(layer "F.SilkS")
		)
		(fp_line
			(start 2.65 2.65)
			(end 2.65 2.05)
			(stroke
				(width 0.2)
				(type solid)
			)
			(layer "F.SilkS")
		)
		(fp_circle
			(center -3.3 -2.5)
			(end -3.3 -2.625)
			(stroke
				(width 0.25)
				(type solid)
			)
			(fill no)
			(layer "F.SilkS")
		)
		(pad "1" smd rect
			(at -2.325 -1.5 90)
			(size 0.26 0.9)
			(layers "F.Cu" "F.Mask" "F.Paste")
			(net "NetR40_2")
		)
		(pad "2" smd rect
			(at -2.325 -1 90)
			(size 0.26 0.9)
			(layers "F.Cu" "F.Mask" "F.Paste")
			(net "NetR108_2")
		)
		(pad "3" smd rect
			(at -2.325 -0.5 90)
			(size 0.26 0.9)
			(layers "F.Cu" "F.Mask" "F.Paste")
			(net "+3.3V")
		)
		(pad "4" smd rect
			(at -2.325 0 90)
			(size 0.26 0.9)
			(layers "F.Cu" "F.Mask" "F.Paste")
			(net "GND")
		)
		(pad "5" smd rect
			(at -2.325 0.5 90)
			(size 0.26 0.9)
			(layers "F.Cu" "F.Mask" "F.Paste")
			(net "NetR41_2")
		)
		(pad "6" smd rect
			(at -2.325 1 90)
			(size 0.26 0.9)
			(layers "F.Cu" "F.Mask" "F.Paste")
			(net "SDA")
		)
		(pad "7" smd rect
			(at -2.325 1.5 90)
			(size 0.26 0.9)
			(layers "F.Cu" "F.Mask" "F.Paste")
			(net "SCL")
		)
		(pad "8" smd rect
			(at -1.5 2.325)
			(size 0.26 0.9)
			(layers "F.Cu" "F.Mask" "F.Paste")
			(net "NetD13_4")
		)
		(pad "9" smd rect
			(at -1 2.325)
			(size 0.26 0.9)
			(layers "F.Cu" "F.Mask" "F.Paste")
			(net "NetD13_3")
		)
		(pad "10" smd rect
			(at -0.5 2.325)
			(size 0.26 0.9)
			(layers "F.Cu" "F.Mask" "F.Paste")
			(net "NetD13_2")
		)
		(pad "11" smd rect
			(at 0 2.325)
			(size 0.26 0.9)
			(layers "F.Cu" "F.Mask" "F.Paste")
			(net "GND")
		)
		(pad "12" smd rect
			(at 0.5 2.325)
			(size 0.26 0.9)
			(layers "F.Cu" "F.Mask" "F.Paste")
			(net "NetD14_4")
		)
		(pad "13" smd rect
			(at 1 2.325)
			(size 0.26 0.9)
			(layers "F.Cu" "F.Mask" "F.Paste")
			(net "NetD14_3")
		)
		(pad "14" smd rect
			(at 1.5 2.325)
			(size 0.26 0.9)
			(layers "F.Cu" "F.Mask" "F.Paste")
			(net "NetD14_2")
		)
		(pad "15" smd rect
			(at 2.325 1.5 90)
			(size 0.26 0.9)
			(layers "F.Cu" "F.Mask" "F.Paste")
			(net "NetD15_4")
		)
		(pad "16" smd rect
			(at 2.325 1 90)
			(size 0.26 0.9)
			(layers "F.Cu" "F.Mask" "F.Paste")
			(net "NetD15_3")
		)
		(pad "17" smd rect
			(at 2.325 0.5 90)
			(size 0.26 0.9)
			(layers "F.Cu" "F.Mask" "F.Paste")
			(net "NetD15_2")
		)
		(pad "18" smd rect
			(at 2.325 0 90)
			(size 0.26 0.9)
			(layers "F.Cu" "F.Mask" "F.Paste")
			(net "GND")
		)
		(pad "19" smd rect
			(at 2.325 -0.5 90)
			(size 0.26 0.9)
			(layers "F.Cu" "F.Mask" "F.Paste")
			(net "NetD16_4")
		)
		(pad "20" smd rect
			(at 2.325 -1 90)
			(size 0.26 0.9)
			(layers "F.Cu" "F.Mask" "F.Paste")
			(net "NetD16_3")
		)
		(pad "21" smd rect
			(at 2.325 -1.5 90)
			(size 0.26 0.9)
			(layers "F.Cu" "F.Mask" "F.Paste")
			(net "NetD16_2")
		)
		(pad "22" smd rect
			(at 1.5 -2.325)
			(size 0.26 0.9)
			(layers "F.Cu" "F.Mask" "F.Paste")
			(net "NetD17_4")
		)
		(pad "23" smd rect
			(at 1 -2.325)
			(size 0.26 0.9)
			(layers "F.Cu" "F.Mask" "F.Paste")
			(net "NetD17_3")
		)
		(pad "24" smd rect
			(at 0.5 -2.325)
			(size 0.26 0.9)
			(layers "F.Cu" "F.Mask" "F.Paste")
			(net "NetD17_2")
		)
		(pad "25" smd rect
			(at 0 -2.325)
			(size 0.26 0.9)
			(layers "F.Cu" "F.Mask" "F.Paste")
			(net "GND")
		)
		(pad "26" smd rect
			(at -0.5 -2.325)
			(size 0.26 0.9)
			(layers "F.Cu" "F.Mask" "F.Paste")
			(net "NetD18_4")
		)
		(pad "27" smd rect
			(at -1 -2.325)
			(size 0.26 0.9)
			(layers "F.Cu" "F.Mask" "F.Paste")
			(net "NetD18_3")
		)
		(pad "28" smd rect
			(at -1.5 -2.325)
			(size 0.26 0.9)
			(layers "F.Cu" "F.Mask" "F.Paste")
			(net "NetD18_2")
		)
		(pad "29" smd rect
			(at 0 0)
			(size 3.25 3.25)
			(layers "F.Cu" "F.Mask" "F.Paste")
			(net "GND")
		)
	)
	(footprint "Vault:FP-DO-214AB_SMC_J-Bend-MFG"
		(layer "F.Cu")
		(at 206.6261 98.1162 180)
		(property "Reference" "D23"
			(at 6.208529 -0.80076 90)
			(unlocked yes)
			(layer "F.SilkS")
			(effects
				(font
					(size 0.762 0.762)
					(thickness 0.2286)
				)
			)
		)
		(property "Value" "SMDJ12A"
			(at -6.847071 2.1193 90)
			(unlocked yes)
			(layer "F.SilkS")
			(hide yes)
			(effects
				(font
					(size 0.762 0.762)
					(thickness 0.2286)
				)
			)
		)
		(sheetname "POWER")
		(sheetfile "POWER.kicad_sch")
		(duplicate_pad_numbers_are_jumpers no)
		(fp_line
			(start 3.555 3.11)
			(end -3.555 3.11)
			(stroke
				(width 0.2)
				(type solid)
			)
			(layer "F.SilkS")
		)
		(fp_line
			(start 3.555 2.025)
			(end 3.555 3.11)
			(stroke
				(width 0.2)
				(type solid)
			)
			(layer "F.SilkS")
		)
		(fp_line
			(start 3.555 -3.11)
			(end 3.555 -2.025)
			(stroke
				(width 0.2)
				(type solid)
			)
			(layer "F.SilkS")
		)
		(fp_line
			(start 3.555 -3.11)
			(end -3.555 -3.11)
			(stroke
				(width 0.2)
				(type solid)
			)
			(layer "F.SilkS")
		)
		(fp_line
			(start -3.555 2.025)
			(end -3.555 3.11)
			(stroke
				(width 0.2)
				(type solid)
			)
			(layer "F.SilkS")
		)
		(fp_line
			(start -3.555 -3.11)
			(end -3.555 -2.025)
			(stroke
				(width 0.2)
				(type solid)
			)
			(layer "F.SilkS")
		)
		(fp_circle
			(center -5.05 0)
			(end -5.05 0.125)
			(stroke
				(width 0.25)
				(type solid)
			)
			(fill no)
			(layer "F.SilkS")
		)
		(fp_line
			(start 4.6 3.21)
			(end -4.6 3.21)
			(stroke
				(width 0.2)
				(type solid)
			)
			(layer "F.CrtYd")
		)
		(fp_line
			(start 4.6 -3.21)
			(end 4.6 3.21)
			(stroke
				(width 0.2)
				(type solid)
			)
			(layer "F.CrtYd")
		)
		(fp_line
			(start 4.6 -3.21)
			(end -4.6 -3.21)
			(stroke
				(width 0.2)
				(type solid)
			)
			(layer "F.CrtYd")
		)
		(fp_line
			(start -4.6 -3.21)
			(end -4.6 3.21)
			(stroke
				(width 0.2)
				(type solid)
			)
			(layer "F.CrtYd")
		)
		(fp_line
			(start 4.6 3.21)
			(end -4.6 3.21)
			(stroke
				(width 0.2)
				(type solid)
			)
			(layer "F.Fab")
		)
		(fp_line
			(start 4.6 -3.21)
			(end 4.6 3.21)
			(stroke
				(width 0.2)
				(type solid)
			)
			(layer "F.Fab")
		)
		(fp_line
			(start 4.6 -3.21)
			(end -4.6 -3.21)
			(stroke
				(width 0.2)
				(type solid)
			)
			(layer "F.Fab")
		)
		(fp_line
			(start 0.5 0)
			(end -0.5 0)
			(stroke
				(width 0.1)
				(type solid)
			)
			(layer "F.Fab")
		)
		(fp_line
			(start 0 -0.5)
			(end 0 0.5)
			(stroke
				(width 0.1)
				(type solid)
			)
			(layer "F.Fab")
		)
		(fp_line
			(start -4.6 -3.21)
			(end -4.6 3.21)
			(stroke
				(width 0.2)
				(type solid)
			)
			(layer "F.Fab")
		)
		(fp_text user "${REFERENCE}"
			(at -0.00001 0.09601 180)
			(unlocked yes)
			(layer "F.Fab")
			(effects
				(font
					(face "Arial")
					(size 0.63 0.63)
					(thickness 0.1)
				)
				(justify left bottom)
			)
		)
		(pad "1" smd rect
			(at -3.3 0 180)
			(size 2.4 3.3)
			(layers "F.Cu" "F.Mask" "F.Paste")
			(net "+12V_SENS")
			(solder_mask_margin 0)
			(solder_paste_margin 0)
		)
		(pad "2" smd rect
			(at 3.3 0 180)
			(size 2.4 3.3)
			(layers "F.Cu" "F.Mask" "F.Paste")
			(net "GND")
			(solder_mask_margin 0)
			(solder_paste_margin 0)
		)
	)
	(footprint "Vault:RESC1005X40X25LL05T10"
		(layer "F.Cu")
		(at 125.1261 84.1162)
		(property "Reference" "R96"
			(at 0.0286 -2.773069 0)
			(unlocked yes)
			(layer "F.SilkS")
			(effects
				(font
					(size 0.762 0.762)
					(thickness 0.2286)
				)
			)
		)
		(property "Value" "49.9_1%_0402"
			(at -2.579871 8.823665 270)
			(unlocked yes)
			(layer "F.SilkS")
			(hide yes)
			(effects
				(font
					(size 0.762 0.762)
					(thickness 0.2286)
				)
			)
		)
		(sheetname "USBUart_DipSelects")
		(sheetfile "USBUart_DipSelects.kicad_sch")
		(duplicate_pad_numbers_are_jumpers no)
		(pad "1" smd rect
			(at -0.375 0 90)
			(size 0.45 0.5)
			(layers "F.Cu" "F.Mask" "F.Paste")
			(net "MAC_PPS_OUT")
		)
		(pad "2" smd rect
			(at 0.375 0 90)
			(size 0.45 0.5)
			(layers "F.Cu" "F.Mask" "F.Paste")
			(net "NetR96_2")
		)
	)
	(footprint "Vault:FP-T495D107K016ATE125-MFG"
		(layer "F.Cu")
		(at 219.9261 103.7162 180)
		(property "Reference" "C10"
			(at -4.3 -0.993345 0)
			(unlocked yes)
			(layer "F.SilkS")
			(effects
				(font
					(size 0.762 0.762)
					(thickness 0.2286)
				)
				(justify left bottom)
			)
		)
		(property "Value" "100uF_16V_2917"
			(at 2.5927 -16.320035 0)
			(unlocked yes)
			(layer "F.SilkS")
			(hide yes)
			(effects
				(font
					(size 0.762 0.762)
					(thickness 0.2286)
				)
				(justify left bottom)
			)
		)
		(sheetname "POWER")
		(sheetfile "POWER.kicad_sch")
		(duplicate_pad_numbers_are_jumpers no)
		(fp_line
			(start 5 0)
			(end 4.4 0)
			(stroke
				(width 0.2)
				(type solid)
			)
			(layer "F.SilkS")
		)
		(fp_line
			(start 4.7 -0.3)
			(end 4.7 0.3)
			(stroke
				(width 0.2)
				(type solid)
			)
			(layer "F.SilkS")
		)
		(fp_line
			(start 3.8 2.3)
			(end -3.8 2.3)
			(stroke
				(width 0.2)
				(type solid)
			)
			(layer "F.SilkS")
		)
		(fp_line
			(start 3.8 1.54)
			(end 3.8 2.3)
			(stroke
				(width 0.2)
				(type solid)
			)
			(layer "F.SilkS")
		)
		(fp_line
			(start 3.8 -2.3)
			(end 3.8 -1.54)
			(stroke
				(width 0.2)
				(type solid)
			)
			(layer "F.SilkS")
		)
		(fp_line
			(start 3.8 -2.3)
			(end -3.8 -2.3)
			(stroke
				(width 0.2)
				(type solid)
			)
			(layer "F.SilkS")
		)
		(fp_line
			(start -3.8 1.54)
			(end -3.8 2.3)
			(stroke
				(width 0.2)
				(type solid)
			)
			(layer "F.SilkS")
		)
		(fp_line
			(start -3.8 -2.3)
			(end -3.8 -1.54)
			(stroke
				(width 0.2)
				(type solid)
			)
			(layer "F.SilkS")
		)
		(fp_line
			(start 4.105 2.4)
			(end -4.105 2.4)
			(stroke
				(width 0.2)
				(type solid)
			)
			(layer "F.CrtYd")
		)
		(fp_line
			(start 4.105 -2.4)
			(end 4.105 2.4)
			(stroke
				(width 0.2)
				(type solid)
			)
			(layer "F.CrtYd")
		)
		(fp_line
			(start 4.105 -2.4)
			(end -4.105 -2.4)
			(stroke
				(width 0.2)
				(type solid)
			)
			(layer "F.CrtYd")
		)
		(fp_line
			(start -4.105 -2.4)
			(end -4.105 2.4)
			(stroke
				(width 0.2)
				(type solid)
			)
			(layer "F.CrtYd")
		)
		(fp_line
			(start 4.105 2.4)
			(end -4.105 2.4)
			(stroke
				(width 0.2)
				(type solid)
			)
			(layer "F.Fab")
		)
		(fp_line
			(start 4.105 -2.4)
			(end 4.105 2.4)
			(stroke
				(width 0.2)
				(type solid)
			)
			(layer "F.Fab")
		)
		(fp_line
			(start 4.105 -2.4)
			(end -4.105 -2.4)
			(stroke
				(width 0.2)
				(type solid)
			)
			(layer "F.Fab")
		)
		(fp_line
			(start 0.5 0)
			(end -0.5 0)
			(stroke
				(width 0.1)
				(type solid)
			)
			(layer "F.Fab")
		)
		(fp_line
			(start 0 -0.5)
			(end 0 0.5)
			(stroke
				(width 0.1)
				(type solid)
			)
			(layer "F.Fab")
		)
		(fp_line
			(start -4.105 -2.4)
			(end -4.105 2.4)
			(stroke
				(width 0.2)
				(type solid)
			)
			(layer "F.Fab")
		)
		(fp_text user "${REFERENCE}"
			(at 0 0.28425 180)
			(unlocked yes)
			(layer "F.Fab")
			(effects
				(font
					(face "Arial")
					(size 0.63 0.63)
					(thickness 0.1)
				)
				(justify left bottom)
			)
		)
		(pad "1" smd rect
			(at -3.01 0 180)
			(size 1.99 2.33)
			(layers "F.Cu" "F.Mask" "F.Paste")
			(net "GND")
			(solder_mask_margin 0)
			(solder_paste_margin 0)
		)
		(pad "2" smd rect
			(at 3.01 0 180)
			(size 1.99 2.33)
			(layers "F.Cu" "F.Mask" "F.Paste")
			(net "+12V")
			(solder_mask_margin 0)
			(solder_paste_margin 0)
		)
	)
	(footprint "Vault:CAPC1608X87X45ML20T05"
		(layer "F.Cu")
		(at 80.3761 98.8662 -90)
		(property "Reference" "C26"
			(at 2.7714 -0.026931 90)
			(unlocked yes)
			(layer "F.SilkS")
			(effects
				(font
					(size 0.762 0.762)
					(thickness 0.2286)
				)
			)
		)
		(property "Value" "0.1uF"
			(at 2.069025 2.630671 270)
			(unlocked yes)
			(layer "F.SilkS")
			(hide yes)
			(effects
				(font
					(size 0.762 0.762)
					(thickness 0.2286)
				)
			)
		)
		(sheetname "USER_IO")
		(sheetfile "USER_IO.kicad_sch")
		(duplicate_pad_numbers_are_jumpers no)
		(pad "1" smd rect
			(at -0.7 0)
			(size 1.1 1.05)
			(layers "F.Cu" "F.Mask" "F.Paste")
			(net "+3.3V")
		)
		(pad "2" smd rect
			(at 0.7 0)
			(size 1.1 1.05)
			(layers "F.Cu" "F.Mask" "F.Paste")
			(net "GND")
		)
	)
	(footprint "Vault:RESC1005X40X25NL05T10"
		(layer "F.Cu")
		(at 206.9261 105.8162 90)
		(property "Reference" "R61"
			(at 2.428605 0.226921 90)
			(unlocked yes)
			(layer "F.SilkS")
			(effects
				(font
					(size 0.762 0.762)
					(thickness 0.2286)
				)
			)
		)
		(property "Value" "2.49K_1%_0402"
			(at -2.732271 9.53462 0)
			(unlocked yes)
			(layer "F.SilkS")
			(hide yes)
			(effects
				(font
					(size 0.762 0.762)
					(thickness 0.2286)
				)
			)
		)
		(sheetname "POWER")
		(sheetfile "POWER.kicad_sch")
		(duplicate_pad_numbers_are_jumpers no)
		(pad "1" smd rect
			(at -0.425 0 180)
			(size 0.55 0.6)
			(layers "F.Cu" "F.Mask" "F.Paste")
			(net "P5V_FB")
		)
		(pad "2" smd rect
			(at 0.425 0 180)
			(size 0.55 0.6)
			(layers "F.Cu" "F.Mask" "F.Paste")
			(net "P5V_SENSE")
		)
	)
	(footprint "Vault:FP-LTST-C191TBKT-MFG"
		(layer "F.Cu")
		(at 73.3761 52.1162 90)
		(property "Reference" "D10"
			(at -6.5214 0.026921 90)
			(unlocked yes)
			(layer "F.SilkS")
			(effects
				(font
					(size 0.762 0.762)
					(thickness 0.2286)
				)
			)
		)
		(property "Value" "BLUE"
			(at 1.2818 2.452871 90)
			(unlocked yes)
			(layer "F.SilkS")
			(hide yes)
			(effects
				(font
					(size 0.762 0.762)
					(thickness 0.2286)
				)
			)
		)
		(sheetname "USER_IO_STATUS")
		(sheetfile "USER_IO_STATUS.kicad_sch")
		(duplicate_pad_numbers_are_jumpers no)
		(fp_line
			(start -0.85 -0.8)
			(end 0.85 -0.8)
			(stroke
				(width 0.2)
				(type solid)
			)
			(layer "F.SilkS")
		)
		(fp_line
			(start -0.85 0.8)
			(end 0.85 0.8)
			(stroke
				(width 0.2)
				(type solid)
			)
			(layer "F.SilkS")
		)
		(fp_circle
			(center -1.75 0)
			(end -1.625 0)
			(stroke
				(width 0.25)
				(type solid)
			)
			(fill no)
			(layer "F.SilkS")
		)
		(fp_line
			(start 1.25 -0.55)
			(end 1.25 0.55)
			(stroke
				(width 0.2)
				(type solid)
			)
			(layer "F.CrtYd")
		)
		(fp_line
			(start -1.25 -0.55)
			(end 1.25 -0.55)
			(stroke
				(width 0.2)
				(type solid)
			)
			(layer "F.CrtYd")
		)
		(fp_line
			(start -1.25 -0.55)
			(end -1.25 0.55)
			(stroke
				(width 0.2)
				(type solid)
			)
			(layer "F.CrtYd")
		)
		(fp_line
			(start -1.25 0.55)
			(end 1.25 0.55)
			(stroke
				(width 0.2)
				(type solid)
			)
			(layer "F.CrtYd")
		)
		(fp_line
			(start 1.25 -0.55)
			(end 1.25 0.55)
			(stroke
				(width 0.2)
				(type solid)
			)
			(layer "F.Fab")
		)
		(fp_line
			(start -1.25 -0.55)
			(end 1.25 -0.55)
			(stroke
				(width 0.2)
				(type solid)
			)
			(layer "F.Fab")
		)
		(fp_line
			(start -1.25 -0.55)
			(end -1.25 0.55)
			(stroke
				(width 0.2)
				(type solid)
			)
			(layer "F.Fab")
		)
		(fp_line
			(start 0 -0.5)
			(end 0 0.5)
			(stroke
				(width 0.1)
				(type solid)
			)
			(layer "F.Fab")
		)
		(fp_line
			(start -0.5 0)
			(end 0.5 0)
			(stroke
				(width 0.1)
				(type solid)
			)
			(layer "F.Fab")
		)
		(fp_line
			(start -1.25 0.55)
			(end 1.25 0.55)
			(stroke
				(width 0.2)
				(type solid)
			)
			(layer "F.Fab")
		)
		(pad "1" smd rect
			(at -0.75 0 90)
			(size 0.8 0.8)
			(layers "F.Cu" "F.Mask" "F.Paste")
			(net "NetD10_1")
			(solder_mask_margin 0)
			(solder_paste_margin 0)
		)
		(pad "2" smd rect
			(at 0.75 0 90)
			(size 0.8 0.8)
			(layers "F.Cu" "F.Mask" "F.Paste")
			(net "+3.3V")
			(solder_mask_margin 0)
			(solder_paste_margin 0)
		)
	)
)
